FILE_TYPE = CONNECTIVITY;
{Allegro Design Entry HDL 16.6-p007 (v16-6-112F) 10/10/2012}
"PAGE_NUMBER" = 142;
0"NC";
1"P3V3_STBY\g";
2"GND\g";
3"P3V3_STBY\g";
4"P3V3_STBY\g";
5"FM_PE_OCP_WAKE_N";
6"FM_PE_M2_WAKE_N";
7"FM_PE_BMC_WAKE_N";
8"FM_PE_SPRV_WAKE_N";
9"FM_PE_SLOTX24_WAKE_N";
10"PU_TRI_STATE_EN";
11"FM_ALL_WAKE_N";
12"IRQ_LVC3_WAKE_R_N";
13"IRQ_LVC3_WAKE_N";
%"TTL1G126_A"
"1","(-3525,2275)","6","mstr_ttl","I1";
;
CDS_SEC"1"
CDS_LIB"mstr_ttl"
SEC_TYPE"SOT"
BOM_COST"SB"
SEC"1"
ROOM"PCIE_WAKE_BUFFER"
CDS_LOCATION"U8E4"
PACK_TYPE"SOT"
PART_NUMBER"A79322-001"
VALUE"74HC1G126"
MATERIAL"IC"
LOCATION"U8E4"
POWER_GROUP"VCC=P3V3_STBY;GND=GND;";
"OE"
$PN"1"10;
"Y"
$PN"4"12;
"A"
$PN"2"11;
%"RES"
"1","(-4300,3125)","0","mstr_discrete","I18";
;
CDS_SEC"1"
SEC"1"
SEC_TYPE"0402"
ROOM"PCIE_WAKE_BUFFER"
BOM_COST"SB"
CDS_LOCATION"R8E29"
CDS_LIB"mstr_discrete"
PACK_TYPE"0402"
MATERIAL"EMPTY"
PART_NUMBER"G21497-005"
LOCATION"R8E29"
TOLERANCE"5%"
VALUE"0.0"
WATTAGE"1/16W";
"B"
$PN"2"11;
"A"
$PN"1"7;
%"RES"
"1","(-2625,2275)","0","mstr_discrete","I2";
;
CDS_SEC"1"
ROOM"PCIE_WAKE_BUFFER"
CDS_LOCATION"R8E17"
SEC"1"
BOM_COST"SB"
SEC_TYPE"0402"
CDS_LIB"mstr_discrete"
PACK_TYPE"0402"
PART_NUMBER"G21796-074"
MATERIAL"CHIP"
LOCATION"R8E17"
TOLERANCE"1%"
WATTAGE"1/16W"
VALUE"33.2";
"B"
$PN"2"13;
"A"
$PN"1"12;
%"CAP_A"
"1","(-3500,1550)","0","dev_discrete","I20";
;
BOM_COST"SB"
SEC_TYPE"0402V"
SEC"1"
ROOM"PCIE_WAKE_BUFFER"
CDS_LOCATION"C8E5"
CDS_SEC"1"
CDS_LIB"dev_discrete"
VALUE"0.1UF"
VOLTAGE"16V"
LOCATION"C8E5"
PACK_TYPE"0402V"
PART_NUMBER"A36096-030"
MATERIAL"X7R"
TOLERANCE"10%";
"B"
$PN"2"2;
"A"
$PN"1"1;
%"P3V3_STBY"
"1","(-3500,1775)","0","mstr_symbols","I21";
;
HDL_POWER"P3V3_STBY"
BODY_TYPE"PLUMBING"
SIZE"1B"
CDS_LIB"mstr_symbols"
VOLTAGE"3.3V";
"G\NAC"1;
%"GND"
"1","(-3500,1250)","0","mstr_symbols","I22";
;
HDL_POWER"GND"
BODY_TYPE"PLUMBING"
CDS_LIB"mstr_symbols"
SIZE"1B"
VOLTAGE"0.0V";
"A\NAC"2;
%"RES"
"2","(-3825,3425)","0","mstr_discrete","I23";
;
CDS_SEC"1"
SEC_TYPE"0402"
SEC"1"
ROOM"PCIE_WAKE_BUFFER"
CDS_LOCATION"R8E30"
CDS_LIB"mstr_discrete"
PART_NUMBER"G21796-016"
WATTAGE"1/16W"
MATERIAL"CHIP"
LOCATION"R8E30"
VALUE"10.0K"
TOLERANCE"1%"
PACK_TYPE"0402";
"A"
$PN"1"3;
"B"
$PN"2"11;
%"P3V3_STBY"
"1","(-3825,3750)","0","mstr_symbols","I24";
;
HDL_POWER"P3V3_STBY"
BODY_TYPE"PLUMBING"
SIZE"1B"
CDS_LIB"mstr_symbols"
VOLTAGE"3.3V";
"G\NAC"3;
%"RES"
"2","(-4650,3425)","0","mstr_discrete","I28";
;
CDS_SEC"1"
ROOM"PCIE_WAKE_BUFFER"
SEC"1"
SEC_TYPE"0402"
CDS_LOCATION"R8E36"
CDS_LIB"mstr_discrete"
TOLERANCE"1%"
LOCATION"R8E36"
VALUE"10.0K"
WATTAGE"1/16W"
MATERIAL"CHIP"
PACK_TYPE"0402"
PART_NUMBER"G21796-016";
"A"
$PN"1"3;
"B"
$PN"2"9;
%"RES"
"1","(-3050,2700)","0","mstr_discrete","I3";
;
CDS_SEC"1"
CDS_LIB"mstr_discrete"
CDS_LOCATION"R8E23"
SEC_TYPE"0402"
ROOM"PCIE_WAKE_BUFFER"
SEC"1"
BOM_COST"SB"
TOLERANCE"1%"
MATERIAL"CHIP"
PACK_TYPE"0402"
PART_NUMBER"G21796-072"
LOCATION"R8E23"
VALUE"4.75K"
WATTAGE"1/16W";
"B"
$PN"2"4;
"A"
$PN"1"10;
%"RES"
"1","(-4350,2275)","0","mstr_discrete","I30";
;
CDS_SEC"1"
CDS_LIB"mstr_discrete"
ROOM"PCIE_WAKE_BUFFER"
CDS_LOCATION"R8E26"
SEC"1"
SEC_TYPE"0402"
MATERIAL"CHIP"
TOLERANCE"5%"
PART_NUMBER"G21497-005"
LOCATION"R8E26"
WATTAGE"1/16W"
PACK_TYPE"0402"
VALUE"0.0";
"B"
$PN"2"11;
"A"
$PN"1"5;
%"RES"
"1","(-4075,2475)","0","mstr_discrete","I31";
;
CDS_SEC"1"
CDS_LIB"mstr_discrete"
ROOM"PCIE_WAKE_BUFFER"
SEC"1"
SEC_TYPE"0402"
CDS_LOCATION"R8E28"
TOLERANCE"5%"
MATERIAL"CHIP"
PART_NUMBER"G21497-005"
LOCATION"R8E28"
VALUE"0.0"
PACK_TYPE"0402"
WATTAGE"1/16W";
"B"
$PN"2"11;
"A"
$PN"1"9;
%"RES"
"1","(-4350,2675)","0","mstr_discrete","I32";
;
CDS_SEC"1"
CDS_LIB"mstr_discrete"
ROOM"PCIE_WAKE_BUFFER"
CDS_LOCATION"R8E27"
SEC"1"
SEC_TYPE"0402"
TOLERANCE"5%"
LOCATION"R8E27"
PACK_TYPE"0402"
VALUE"0.0"
MATERIAL"CHIP"
PART_NUMBER"G21497-005"
WATTAGE"1/16W";
"B"
$PN"2"11;
"A"
$PN"1"6;
%"RES"
"1","(-4075,2900)","0","mstr_discrete","I33";
;
CDS_SEC"1"
CDS_LIB"mstr_discrete"
SEC"1"
SEC_TYPE"0402"
ROOM"PCIE_WAKE_BUFFER"
CDS_LOCATION"R8E21"
TOLERANCE"5%"
MATERIAL"CHIP"
PART_NUMBER"G21497-005"
LOCATION"R8E21"
PACK_TYPE"0402"
VALUE"0.0"
WATTAGE"1/16W";
"B"
$PN"2"11;
"A"
$PN"1"8;
%"P3V3_STBY"
"1","(-2525,2950)","0","mstr_symbols","I4";
;
HDL_POWER"P3V3_STBY"
BODY_TYPE"PLUMBING"
SIZE"1B"
CDS_LIB"mstr_symbols"
VOLTAGE"3.3V";
"G\NAC"4;
END.
